# SCM (Grand Teton) — schematic netlist excerpt (pin names and nets, part order shuffled) for the footprints in the layout excerpt that follows; sources: Cadence DE-HDL packaged netlist, KiCad conversion of 12092022_DA0F0TMDCD0_F0T_Management_Board_D_brd_V3_OCP.brd

C100  Q_CAP  0.1UF 25V 10% X7R  pkg 0402  page 16 : A = P1V8_AUX ; B = GND
R469  Q_RES  33.2 1% CHIP  pkg 0402LF  page 13 : A = SPI_BMC_TPM_MISO_R1 ; B = SPI_BMC_TPM_MISO

(kicad_pcb
	(version 20260206)
	(generator "pcbnew")
	(generator_version "10.0")
	(general
		(thickness 1.6)
		(legacy_teardrops no)
	)
	(paper "A4")
	(title_block
		(title "12092022_DA0F0TMDCD0_F0T_Management_Board_D_brd_V3_OCP.brd")
		(comment 1 "Grand Teton / footprints 849-850 of 1440")
	)
	(layers
		(0 "F.Cu" signal "TOP")
		(4 "In1.Cu" signal "GND")
		(6 "In2.Cu" signal "IN1")
		(8 "In3.Cu" signal "GND1")
		(10 "In4.Cu" signal "IN2")
		(12 "In5.Cu" signal "VCC")
		(14 "In6.Cu" signal "VCC1")
		(16 "In7.Cu" signal "IN3")
		(18 "In8.Cu" signal "GND2")
		(20 "In9.Cu" signal "IN4")
		(22 "In10.Cu" signal "GND3")
		(2 "B.Cu" signal "BOTTOM")
		(9 "F.Adhes" user "F.Adhesive")
		(11 "B.Adhes" user "B.Adhesive")
		(13 "F.Paste" user "Package Geometry/Pastemask Top")
		(15 "B.Paste" user "Package Geometry/Pastemask Bottom")
		(5 "F.SilkS" user "Ref Des/Silkscreen Top")
		(7 "B.SilkS" user "Ref Des/Silkscreen Bottom")
		(1 "F.Mask" user "Board Geometry/Soldermask Top")
		(3 "B.Mask" user "Board Geometry/Soldermask Bottom")
		(17 "Dwgs.User" user "User.Drawings")
		(19 "Cmts.User" user "User.Comments")
		(21 "Eco1.User" user "User.Eco1")
		(23 "Eco2.User" user "User.Eco2")
		(25 "Edge.Cuts" user "Board Geometry/Outline")
		(27 "Margin" user)
		(31 "F.CrtYd" user "Package Geometry/Place Bound Top")
		(29 "B.CrtYd" user "Package Geometry/Place Bound Bottom")
		(35 "F.Fab" user "Ref Des/Assembly Top")
		(33 "B.Fab" user "Ref Des/Assembly Bottom")
	)
	(footprint ""
		(layer "B.Cu")
		(at 56.256174 -43.77436)
		(property "Reference" "C100"
			(at 0 0 0)
			(layer "B.SilkS")
			(hide yes)
			(effects
				(font
					(size 1.27 1.27)
				)
				(justify mirror)
			)
		)
		(property "Value" ""
			(at 0 0 0)
			(layer "B.Fab")
			(effects
				(font
					(size 1.27 1.27)
				)
				(justify mirror)
			)
		)
		(duplicate_pad_numbers_are_jumpers no)
		(fp_line
			(start -0.7874 -0.4064)
			(end -0.7874 0.4064)
			(stroke
				(width 0.1524)
				(type default)
			)
			(layer "B.SilkS")
		)
		(fp_line
			(start -0.7874 0.4064)
			(end 0.7874 0.4064)
			(stroke
				(width 0.1524)
				(type default)
			)
			(layer "B.SilkS")
		)
		(fp_line
			(start 0.7874 -0.4064)
			(end -0.7874 -0.4064)
			(stroke
				(width 0.1524)
				(type default)
			)
			(layer "B.SilkS")
		)
		(fp_line
			(start 0.7874 0.4064)
			(end 0.7874 -0.4064)
			(stroke
				(width 0.1524)
				(type default)
			)
			(layer "B.SilkS")
		)
		(fp_line
			(start -0.67945 -0.3048)
			(end -0.67945 0.3048)
			(stroke
				(width 0.1)
				(type default)
			)
			(layer "B.Fab")
		)
		(fp_line
			(start -0.67945 0.3048)
			(end -0.120396 0.3048)
			(stroke
				(width 0.1)
				(type default)
			)
			(layer "B.Fab")
		)
		(fp_line
			(start -0.12065 -0.3048)
			(end -0.67945 -0.3048)
			(stroke
				(width 0.1)
				(type default)
			)
			(layer "B.Fab")
		)
		(fp_line
			(start -0.12065 -0.2794)
			(end -0.12065 -0.3048)
			(stroke
				(width 0.1)
				(type default)
			)
			(layer "B.Fab")
		)
		(fp_line
			(start -0.120396 0.2794)
			(end 0.12065 0.2794)
			(stroke
				(width 0.1)
				(type default)
			)
			(layer "B.Fab")
		)
		(fp_line
			(start -0.120396 0.3048)
			(end -0.120396 0.2794)
			(stroke
				(width 0.1)
				(type default)
			)
			(layer "B.Fab")
		)
		(fp_line
			(start 0.12065 -0.305054)
			(end 0.12065 -0.2794)
			(stroke
				(width 0.1)
				(type default)
			)
			(layer "B.Fab")
		)
		(fp_line
			(start 0.12065 -0.2794)
			(end -0.12065 -0.2794)
			(stroke
				(width 0.1)
				(type default)
			)
			(layer "B.Fab")
		)
		(fp_line
			(start 0.12065 0.2794)
			(end 0.12065 0.3048)
			(stroke
				(width 0.1)
				(type default)
			)
			(layer "B.Fab")
		)
		(fp_line
			(start 0.12065 0.3048)
			(end 0.67945 0.3048)
			(stroke
				(width 0.1)
				(type default)
			)
			(layer "B.Fab")
		)
		(fp_line
			(start 0.67945 -0.305054)
			(end 0.12065 -0.305054)
			(stroke
				(width 0.1)
				(type default)
			)
			(layer "B.Fab")
		)
		(fp_line
			(start 0.67945 0.3048)
			(end 0.67945 -0.305054)
			(stroke
				(width 0.1)
				(type default)
			)
			(layer "B.Fab")
		)
		(pad "1" smd circle
			(at 0.40005 0 180)
			(size 0 0)
			(layers "B.Cu" "B.Mask" "B.Paste")
			(net "P1V8_AUX")
		)
		(pad "2" smd circle
			(at -0.40005 0 180)
			(size 0 0)
			(layers "B.Cu" "B.Mask" "B.Paste")
			(net "GND")
		)
	)
	(footprint ""
		(layer "B.Cu")
		(at 61.64326 -65.85585 -90)
		(property "Reference" "R469"
			(at 0 0 90)
			(layer "B.SilkS")
			(hide yes)
			(effects
				(font
					(size 1.27 1.27)
				)
				(justify mirror)
			)
		)
		(property "Value" ""
			(at 0 0 90)
			(layer "B.Fab")
			(effects
				(font
					(size 1.27 1.27)
				)
				(justify mirror)
			)
		)
		(duplicate_pad_numbers_are_jumpers no)
		(fp_line
			(start -0.7874 0.4064)
			(end 0.7874 0.4064)
			(stroke
				(width 0.1524)
				(type default)
			)
			(layer "B.SilkS")
		)
		(fp_line
			(start 0.7874 0.4064)
			(end 0.7874 -0.4064)
			(stroke
				(width 0.1524)
				(type default)
			)
			(layer "B.SilkS")
		)
		(fp_line
			(start -0.7874 -0.4064)
			(end -0.7874 0.4064)
			(stroke
				(width 0.1524)
				(type default)
			)
			(layer "B.SilkS")
		)
		(fp_line
			(start 0.7874 -0.4064)
			(end -0.7874 -0.4064)
			(stroke
				(width 0.1524)
				(type default)
			)
			(layer "B.SilkS")
		)
		(fp_line
			(start -0.67945 0.3048)
			(end -0.120396 0.3048)
			(stroke
				(width 0.1)
				(type default)
			)
			(layer "B.Fab")
		)
		(fp_line
			(start -0.120396 0.3048)
			(end -0.120396 0.2794)
			(stroke
				(width 0.1)
				(type default)
			)
			(layer "B.Fab")
		)
		(fp_line
			(start 0.12065 0.3048)
			(end 0.67945 0.3048)
			(stroke
				(width 0.1)
				(type default)
			)
			(layer "B.Fab")
		)
		(fp_line
			(start 0.67945 0.3048)
			(end 0.67945 -0.305054)
			(stroke
				(width 0.1)
				(type default)
			)
			(layer "B.Fab")
		)
		(fp_line
			(start -0.120396 0.2794)
			(end 0.12065 0.2794)
			(stroke
				(width 0.1)
				(type default)
			)
			(layer "B.Fab")
		)
		(fp_line
			(start 0.12065 0.2794)
			(end 0.12065 0.3048)
			(stroke
				(width 0.1)
				(type default)
			)
			(layer "B.Fab")
		)
		(fp_line
			(start -0.12065 -0.2794)
			(end -0.12065 -0.3048)
			(stroke
				(width 0.1)
				(type default)
			)
			(layer "B.Fab")
		)
		(fp_line
			(start 0.12065 -0.2794)
			(end -0.12065 -0.2794)
			(stroke
				(width 0.1)
				(type default)
			)
			(layer "B.Fab")
		)
		(fp_line
			(start -0.67945 -0.3048)
			(end -0.67945 0.3048)
			(stroke
				(width 0.1)
				(type default)
			)
			(layer "B.Fab")
		)
		(fp_line
			(start -0.12065 -0.3048)
			(end -0.67945 -0.3048)
			(stroke
				(width 0.1)
				(type default)
			)
			(layer "B.Fab")
		)
		(fp_line
			(start 0.12065 -0.305054)
			(end 0.12065 -0.2794)
			(stroke
				(width 0.1)
				(type default)
			)
			(layer "B.Fab")
		)
		(fp_line
			(start 0.67945 -0.305054)
			(end 0.12065 -0.305054)
			(stroke
				(width 0.1)
				(type default)
			)
			(layer "B.Fab")
		)
		(pad "1" smd circle
			(at 0.40005 0 90)
			(size 0 0)
			(layers "B.Cu" "B.Mask" "B.Paste")
			(net "SPI_BMC_TPM_MISO_R1")
		)
		(pad "2" smd circle
			(at -0.40005 0 90)
			(size 0 0)
			(layers "B.Cu" "B.Mask" "B.Paste")
			(net "SPI_BMC_TPM_MISO")
		)
	)
)
